#ISCELL
  mstr_misc dns *
  *
#ISCELL
  pure_quanta quanta_title_block_c *
  *
#ISCELL
  standard offpage *
  page385_i100
#ISCELL
  pure_quanta_power p1v0 *
  page385_i101
#ISCELL
  standard offpage *
  page385_i102
#ISCELL
  standard offpage *
  page385_i103
#CELL
  pure_quanta q_res *
  page385_i111
#ISCELL
  pure_quanta_power universal_gnd *
  page385_i112
#ISCELL
  standard offpage *
  page385_i113
#CELL
  pure_quanta q_res *
  page385_i114
#ISCELL
  pure_quanta_power gnd *
  page385_i115
#CELL
  pure_quanta q_res *
  page385_i116
#ISCELL
  pure_quanta_power p1v0 *
  page385_i117
#ISCELL
  standard offpage *
  page385_i118
#CELL
  pure_quanta q_res *
  page385_i119
#ISCELL
  pure_quanta_power universal_gnd *
  page385_i120
#CELL
  pure_quanta q_res *
  page385_i121
#ISCELL
  standard offpage *
  page385_i122
#CELL
  pure_quanta q_res *
  page385_i123
#ISCELL
  pure_quanta_power gnd *
  page385_i128
#ISCELL
  standard offpage *
  page385_i133
#ISCELL
  standard offpage *
  page385_i134
#ISCELL
  standard offpage *
  page385_i135
#ISCELL
  standard offpage *
  page385_i136
#ISCELL
  standard offpage *
  page385_i137
#ISCELL
  standard offpage *
  page385_i138
#ISCELL
  standard offpage *
  page385_i139
#CELL
  pure_quanta q_res *
  page385_i143
#ISCELL
  pure_quanta_power p1v0 *
  page385_i144
#CELL
  pure_quanta q_res *
  page385_i145
#CELL
  pure_quanta q_res *
  page385_i146
#CELL
  pure_quanta q_res *
  page385_i147
#ISCELL
  standard offpage *
  page385_i21
#ISCELL
  standard offpage *
  page385_i22
#ISCELL
  pure_quanta_power universal_gnd *
  page385_i23
#CELL
  pure_quanta q_res *
  page385_i25
#ISCELL
  pure_quanta_power p1v0 *
  page385_i26
#CELL
  pure_quanta q_res *
  page385_i27
#CELL
  pure_quanta q_res *
  page385_i28
#CELL
  pure_quanta q_res *
  page385_i29
#CELL
  pure_quanta q_res *
  page385_i30
#CELL
  pure_quanta q_res *
  page385_i31
#ISCELL
  pure_quanta_power p1v0 *
  page385_i32
#ISCELL
  standard offpage *
  page385_i33
#ISCELL
  standard offpage *
  page385_i34
#ISCELL
  pure_quanta_power universal_gnd *
  page385_i35
#ISCELL
  pure_quanta_power universal_gnd *
  page385_i36
#CELL
  pure_quanta q_res *
  page385_i37
#CELL
  pure_quanta q_res *
  page385_i38
#CELL
  pure_quanta q_res *
  page385_i39
#CELL
  pure_quanta q_res *
  page385_i40
#CELL
  pure_quanta q_res *
  page385_i41
#CELL
  pure_quanta q_res *
  page385_i42
#ISCELL
  standard offpage *
  page385_i43
#ISCELL
  standard offpage *
  page385_i44
#ISCELL
  standard offpage *
  page385_i45
#ISCELL
  standard offpage *
  page385_i46
#ISCELL
  standard offpage *
  page385_i47
#ISCELL
  standard offpage *
  page385_i48
#CELL
  pure_quanta q_res *
  page385_i49
#CELL
  pure_quanta q_res *
  page385_i50
#ISCELL
  standard offpage *
  page385_i51
#ISCELL
  standard offpage *
  page385_i52
#CELL
  pure_quanta pt5161lrs *
  page385_i53
#ISCELL
  standard offpage *
  page385_i54
#ISCELL
  standard offpage *
  page385_i55
#ISCELL
  standard offpage *
  page385_i56
#CELL
  pure_quanta q_res *
  page385_i57
#CELL
  pure_quanta q_res *
  page385_i58
#ISCELL
  pure_quanta_power universal_gnd *
  page385_i59
#CELL
  pure_quanta q_res *
  page385_i60
#CELL
  pure_quanta q_res *
  page385_i61
#CELL
  pure_quanta q_res *
  page385_i62
#CELL
  pure_quanta q_res *
  page385_i63
#ISCELL
  standard offpage *
  page385_i64
#ISCELL
  standard offpage *
  page385_i65
#ISCELL
  standard offpage *
  page385_i66
#ISCELL
  standard offpage *
  page385_i67
#ISCELL
  standard offpage *
  page385_i68
#ISCELL
  standard offpage *
  page385_i69
#ISCELL
  pure_quanta_power universal_gnd *
  page385_i70
#CELL
  pure_quanta q_res *
  page385_i71
#CELL
  pure_quanta q_res *
  page385_i72
#ISCELL
  standard offpage *
  page385_i73
#ISCELL
  pure_quanta_power p1v0 *
  page385_i74
#ISCELL
  pure_quanta_power universal_gnd *
  page385_i75
#CELL
  pure_quanta q_res *
  page385_i76
#CELL
  pure_quanta q_res *
  page385_i77
#ISCELL
  standard offpage *
  page385_i79
#ISCELL
  standard offpage *
  page385_i80
#ISCELL
  standard offpage *
  page385_i82
#ISCELL
  standard offpage *
  page385_i83
#ISCELL
  standard offpage *
  page385_i84
#ISCELL
  pure_quanta_power universal_gnd *
  page385_i85
#CELL
  pure_quanta q_res *
  page385_i86
#CELL
  pure_quanta q_res *
  page385_i87
#CELL
  pure_quanta q_res *
  page385_i88
#CELL
  pure_quanta q_res *
  page385_i89
#CELL
  pure_quanta q_res *
  page385_i90
#CELL
  pure_quanta q_res *
  page385_i91
#ISCELL
  pure_quanta_power p1v0 *
  page385_i92
#ISCELL
  pure_quanta_power gnd *
  page385_i93
#ISCELL
  pure_quanta_power gnd *
  page385_i94
#ISCELL
  standard offpage *
  page385_i95
#CELL
  pure_quanta q_res *
  page385_i96
#CELL
  pure_quanta q_res *
  page385_i97
#CELL
  pure_quanta q_res *
  page385_i98
#ISCELL
  standard offpage *
  page385_i99
